# BASEBOARD_FAB2 (Tioga Pass) — schematic netlist excerpt (pin names and nets, part order shuffled) for the footprints in the layout excerpt that follows; sources: Cadence DE-HDL packaged netlist, KiCad conversion of Wiwynn_Tioga_Pass_MB.brd

R1D7  RES  1.00K 1% CHIP  pkg 0402  page 206 : A = P3V3_STBY ; B = FM_PVCCIN_CPU1_PWR_IN_ALERT_N
CT53  CAP  1000PF 50V 10% X7R  pkg 0402LF  page 216 : A = VR_PVDDQ_ABC_PH2_SW ; B = VR_PVDDQ_ABC_PH2_SW_RC

(kicad_pcb
	(version 20260206)
	(generator "pcbnew")
	(generator_version "10.0")
	(general
		(thickness 1.6)
		(legacy_teardrops no)
	)
	(paper "A4")
	(title_block
		(title "Wiwynn_Tioga_Pass_MB.brd")
		(comment 1 "Tioga Pass / footprints 365-366 of 4770")
	)
	(layers
		(0 "F.Cu" signal "TOP")
		(4 "In1.Cu" signal "L2GND")
		(6 "In2.Cu" signal "L3")
		(8 "In3.Cu" signal "L4GND")
		(10 "In4.Cu" signal "L5")
		(12 "In5.Cu" signal "L6GND")
		(14 "In6.Cu" signal "L7VCC")
		(16 "In7.Cu" signal "L8VCC")
		(18 "In8.Cu" signal "L9GND")
		(20 "In9.Cu" signal "L10")
		(22 "In10.Cu" signal "L11GND")
		(24 "In11.Cu" signal "L12")
		(26 "In12.Cu" signal "L13GND")
		(2 "B.Cu" signal "BOTTOM")
		(9 "F.Adhes" user "F.Adhesive")
		(11 "B.Adhes" user "B.Adhesive")
		(13 "F.Paste" user "Package Geometry/Pastemask Top")
		(15 "B.Paste" user "Package Geometry/Pastemask Bottom")
		(5 "F.SilkS" user "Ref Des/Silkscreen Top")
		(7 "B.SilkS" user "Ref Des/Silkscreen Bottom")
		(1 "F.Mask" user "Board Geometry/Soldermask Top")
		(3 "B.Mask" user "Board Geometry/Soldermask Bottom")
		(17 "Dwgs.User" user "User.Drawings")
		(19 "Cmts.User" user "User.Comments")
		(21 "Eco1.User" user "User.Eco1")
		(23 "Eco2.User" user "User.Eco2")
		(25 "Edge.Cuts" user "Board Geometry/Outline")
		(27 "Margin" user)
		(31 "F.CrtYd" user "Package Geometry/Place Bound Top")
		(29 "B.CrtYd" user "Package Geometry/Place Bound Bottom")
		(35 "F.Fab" user "Ref Des/Assembly Top")
		(33 "B.Fab" user "Ref Des/Assembly Bottom")
	)
	(footprint ""
		(layer "F.Cu")
		(at 15.24 -86.741 180)
		(property "Reference" "R1D7"
			(at 0 0 180)
			(layer "F.SilkS")
			(hide yes)
			(effects
				(font
					(size 1.27 1.27)
				)
			)
		)
		(property "Value" ""
			(at 0 0 180)
			(layer "F.Fab")
			(effects
				(font
					(size 1.27 1.27)
				)
			)
		)
		(duplicate_pad_numbers_are_jumpers no)
		(fp_rect
			(start 0.2794 -0.1016)
			(end -0.2794 0.9906)
			(stroke
				(width 0)
				(type default)
			)
			(fill no)
			(layer "F.CrtYd")
		)
		(fp_line
			(start 0.2794 0.9906)
			(end 0.2794 -0.1016)
			(stroke
				(width 0.1)
				(type default)
			)
			(layer "F.Fab")
		)
		(fp_line
			(start 0.2794 -0.1016)
			(end -0.2794 -0.1016)
			(stroke
				(width 0.1)
				(type default)
			)
			(layer "F.Fab")
		)
		(fp_line
			(start -0.2794 0.9906)
			(end 0.2794 0.9906)
			(stroke
				(width 0.1)
				(type default)
			)
			(layer "F.Fab")
		)
		(fp_line
			(start -0.2794 -0.1016)
			(end -0.2794 0.9906)
			(stroke
				(width 0.1)
				(type default)
			)
			(layer "F.Fab")
		)
		(pad "1" smd rect
			(at 0 0 180)
			(size 0.508 0.508)
			(layers "F.Cu" "F.Mask" "F.Paste")
			(net "P3V3_STBY")
		)
		(pad "2" smd rect
			(at 0 0.889 180)
			(size 0.508 0.508)
			(layers "F.Cu" "F.Mask" "F.Paste")
			(net "FM_PVCCIN_CPU1_PWR_IN_ALERT_N")
		)
		(zone
			(layer "F.Cu")
			(hatch none 0.5)
			(connect_pads
				(clearance 0)
			)
			(min_thickness 0.25)
			(keepout
				(tracks not_allowed)
				(vias allowed)
				(pads allowed)
				(copperpour not_allowed)
				(footprints allowed)
			)
			(placement
				(enabled no)
				(sheetname "")
			)
			(fill
				(thermal_gap 0.5)
				(thermal_bridge_width 0.5)
				(island_removal_mode 0)
			)
			(polygon
				(pts
					(xy 14.986 -86.995) (xy 15.494 -86.995) (xy 15.494 -87.376) (xy 14.986 -87.376)
				)
			)
		)
		(zone
			(layer "F.Cu")
			(hatch none 0.5)
			(connect_pads
				(clearance 0)
			)
			(min_thickness 0.25)
			(keepout
				(tracks allowed)
				(vias not_allowed)
				(pads allowed)
				(copperpour not_allowed)
				(footprints allowed)
			)
			(placement
				(enabled no)
				(sheetname "")
			)
			(fill
				(thermal_gap 0.5)
				(thermal_bridge_width 0.5)
				(island_removal_mode 0)
			)
			(polygon
				(pts
					(xy 14.986 -86.995) (xy 15.494 -86.995) (xy 15.494 -87.376) (xy 14.986 -87.376)
				)
			)
		)
	)
	(footprint ""
		(layer "F.Cu")
		(at 340.38286 -2.02438 90)
		(property "Reference" "CT53"
			(at -0.8382 -0.67818 90)
			(unlocked yes)
			(layer "F.SilkS")
			(effects
				(font
					(size 0.4064 0.254)
					(thickness 0.1524)
				)
				(justify left)
			)
		)
		(property "Value" ""
			(at 0 0 90)
			(layer "F.Fab")
			(effects
				(font
					(size 1.27 1.27)
				)
			)
		)
		(duplicate_pad_numbers_are_jumpers no)
		(fp_poly
			(pts
				(xy 0.3048 -0.1016) (xy 0.3048 0.9906) (xy -0.3048 0.9906) (xy -0.3048 -0.1016)
			)
			(stroke
				(width 0)
				(type default)
			)
			(fill no)
			(layer "F.CrtYd")
		)
		(fp_line
			(start 0.3048 -0.1016)
			(end -0.3048 -0.1016)
			(stroke
				(width 0.1)
				(type default)
			)
			(layer "F.Fab")
		)
		(fp_line
			(start -0.3048 -0.1016)
			(end -0.3048 0.9906)
			(stroke
				(width 0.1)
				(type default)
			)
			(layer "F.Fab")
		)
		(fp_line
			(start 0.3048 0.9906)
			(end 0.3048 -0.1016)
			(stroke
				(width 0.1)
				(type default)
			)
			(layer "F.Fab")
		)
		(fp_line
			(start -0.3048 0.9906)
			(end 0.3048 0.9906)
			(stroke
				(width 0.1)
				(type default)
			)
			(layer "F.Fab")
		)
		(pad "1" smd rect
			(at 0 0 90)
			(size 0.508 0.508)
			(layers "F.Cu" "F.Mask" "F.Paste")
			(net "VR_PVDDQ_ABC_PH2_SW")
		)
		(pad "2" smd rect
			(at 0 0.889 90)
			(size 0.508 0.508)
			(layers "F.Cu" "F.Mask" "F.Paste")
			(net "VR_PVDDQ_ABC_PH2_SW_RC")
		)
		(zone
			(layer "F.Cu")
			(hatch none 0.5)
			(connect_pads
				(clearance 0)
			)
			(min_thickness 0.25)
			(keepout
				(tracks allowed)
				(vias not_allowed)
				(pads allowed)
				(copperpour not_allowed)
				(footprints allowed)
			)
			(placement
				(enabled no)
				(sheetname "")
			)
			(fill
				(thermal_gap 0.5)
				(thermal_bridge_width 0.5)
				(island_removal_mode 0)
			)
			(polygon
				(pts
					(xy 340.63686 -1.77038) (xy 340.63686 -2.27838) (xy 341.01786 -2.27838) (xy 341.01786 -1.77038)
				)
			)
		)
		(zone
			(layer "F.Cu")
			(hatch none 0.5)
			(connect_pads
				(clearance 0)
			)
			(min_thickness 0.25)
			(keepout
				(tracks not_allowed)
				(vias allowed)
				(pads allowed)
				(copperpour not_allowed)
				(footprints allowed)
			)
			(placement
				(enabled no)
				(sheetname "")
			)
			(fill
				(thermal_gap 0.5)
				(thermal_bridge_width 0.5)
				(island_removal_mode 0)
			)
			(polygon
				(pts
					(xy 341.01786 -1.77038) (xy 341.01786 -2.27838) (xy 340.63686 -2.27838) (xy 340.63686 -1.77038)
				)
			)
		)
	)
)
